# S9S_MB_2U (Grand Teton) — schematic netlist excerpt (pin names and nets, part order shuffled) for the footprints in the layout excerpt that follows; sources: Cadence DE-HDL packaged netlist, KiCad conversion of 03242023_DA0F0TMBIJ0_F0T_Motherboard_J_brd_V01_OCP.brd

PC486_P1_7  Q_CAP  1UF 16V 10% X6S  pkg C0402  page 288 : A = SW_P12V_PVCCIN_CPU1_FLT ; B = GND
C251  Q_CAP  10UF 6.3V 20% X6S  pkg C0402  page 77 : A = PVCCIN_CPU1 ; B = GND

(kicad_pcb
	(version 20260206)
	(generator "pcbnew")
	(generator_version "10.0")
	(general
		(thickness 1.6)
		(legacy_teardrops no)
	)
	(paper "A4")
	(title_block
		(title "03242023_DA0F0TMBIJ0_F0T_Motherboard_J_brd_V01_OCP.brd")
		(comment 1 "Grand Teton / footprints 3594-3595 of 6105")
	)
	(layers
		(0 "F.Cu" signal "TOP")
		(4 "In1.Cu" signal "GND")
		(6 "In2.Cu" signal "IN1")
		(8 "In3.Cu" signal "GND1")
		(10 "In4.Cu" signal "IN2")
		(12 "In5.Cu" signal "GND2")
		(14 "In6.Cu" signal "IN3")
		(16 "In7.Cu" signal "GND3")
		(18 "In8.Cu" signal "VCC")
		(20 "In9.Cu" signal "VCC1")
		(22 "In10.Cu" signal "GND4")
		(24 "In11.Cu" signal "IN4")
		(26 "In12.Cu" signal "GND5")
		(28 "In13.Cu" signal "IN5")
		(30 "In14.Cu" signal "GND6")
		(32 "In15.Cu" signal "IN6")
		(34 "In16.Cu" signal "GND7")
		(2 "B.Cu" signal "BOTTOM")
		(9 "F.Adhes" user "F.Adhesive")
		(11 "B.Adhes" user "B.Adhesive")
		(13 "F.Paste" user "Package Geometry/Pastemask Top")
		(15 "B.Paste" user "Package Geometry/Pastemask Bottom")
		(5 "F.SilkS" user "Ref Des/Silkscreen Top")
		(7 "B.SilkS" user "Ref Des/Silkscreen Bottom")
		(1 "F.Mask" user "Board Geometry/Soldermask Top")
		(3 "B.Mask" user "Board Geometry/Soldermask Bottom")
		(17 "Dwgs.User" user "User.Drawings")
		(19 "Cmts.User" user "User.Comments")
		(21 "Eco1.User" user "User.Eco1")
		(23 "Eco2.User" user "User.Eco2")
		(25 "Edge.Cuts" user "Board Geometry/Outline")
		(27 "Margin" user)
		(31 "F.CrtYd" user "Package Geometry/Place Bound Top")
		(29 "B.CrtYd" user "Package Geometry/Place Bound Bottom")
		(35 "F.Fab" user "Ref Des/Assembly Top")
		(33 "B.Fab" user "Ref Des/Assembly Bottom")
	)
	(footprint ""
		(layer "F.Cu")
		(at 105.3084 -251.375672 90)
		(property "Reference" "C251"
			(at 0 0 90)
			(layer "F.SilkS")
			(hide yes)
			(effects
				(font
					(size 1.27 1.27)
				)
			)
		)
		(property "Value" ""
			(at 0 0 90)
			(layer "F.Fab")
			(effects
				(font
					(size 1.27 1.27)
				)
			)
		)
		(duplicate_pad_numbers_are_jumpers no)
		(fp_line
			(start 0.7874 -0.4064)
			(end 0.7874 0.4064)
			(stroke
				(width 0.1524)
				(type default)
			)
			(layer "F.SilkS")
		)
		(fp_line
			(start -0.7874 -0.4064)
			(end 0.7874 -0.4064)
			(stroke
				(width 0.1524)
				(type default)
			)
			(layer "F.SilkS")
		)
		(fp_line
			(start 0.7874 0.4064)
			(end -0.7874 0.4064)
			(stroke
				(width 0.1524)
				(type default)
			)
			(layer "F.SilkS")
		)
		(fp_line
			(start -0.7874 0.4064)
			(end -0.7874 -0.4064)
			(stroke
				(width 0.1524)
				(type default)
			)
			(layer "F.SilkS")
		)
		(fp_line
			(start -0.12065 -0.305054)
			(end -0.12065 -0.2794)
			(stroke
				(width 0.1)
				(type default)
			)
			(layer "F.Fab")
		)
		(fp_line
			(start -0.67945 -0.305054)
			(end -0.12065 -0.305054)
			(stroke
				(width 0.1)
				(type default)
			)
			(layer "F.Fab")
		)
		(fp_line
			(start 0.67945 -0.3048)
			(end 0.67945 0.3048)
			(stroke
				(width 0.1)
				(type default)
			)
			(layer "F.Fab")
		)
		(fp_line
			(start 0.12065 -0.3048)
			(end 0.67945 -0.3048)
			(stroke
				(width 0.1)
				(type default)
			)
			(layer "F.Fab")
		)
		(fp_line
			(start 0.12065 -0.2794)
			(end 0.12065 -0.3048)
			(stroke
				(width 0.1)
				(type default)
			)
			(layer "F.Fab")
		)
		(fp_line
			(start -0.12065 -0.2794)
			(end 0.12065 -0.2794)
			(stroke
				(width 0.1)
				(type default)
			)
			(layer "F.Fab")
		)
		(fp_line
			(start 0.120396 0.2794)
			(end -0.12065 0.2794)
			(stroke
				(width 0.1)
				(type default)
			)
			(layer "F.Fab")
		)
		(fp_line
			(start -0.12065 0.2794)
			(end -0.12065 0.3048)
			(stroke
				(width 0.1)
				(type default)
			)
			(layer "F.Fab")
		)
		(fp_line
			(start 0.67945 0.3048)
			(end 0.120396 0.3048)
			(stroke
				(width 0.1)
				(type default)
			)
			(layer "F.Fab")
		)
		(fp_line
			(start 0.120396 0.3048)
			(end 0.120396 0.2794)
			(stroke
				(width 0.1)
				(type default)
			)
			(layer "F.Fab")
		)
		(fp_line
			(start -0.12065 0.3048)
			(end -0.67945 0.3048)
			(stroke
				(width 0.1)
				(type default)
			)
			(layer "F.Fab")
		)
		(fp_line
			(start -0.67945 0.3048)
			(end -0.67945 -0.305054)
			(stroke
				(width 0.1)
				(type default)
			)
			(layer "F.Fab")
		)
		(pad "1" smd circle
			(at -0.40005 0 90)
			(size 0 0)
			(layers "F.Cu" "F.Mask" "F.Paste")
			(net "PVCCIN_CPU1")
		)
		(pad "2" smd circle
			(at 0.40005 0 90)
			(size 0 0)
			(layers "F.Cu" "F.Mask" "F.Paste")
			(net "GND")
		)
	)
	(footprint ""
		(layer "F.Cu")
		(at 84.270342 -343.015062 -90)
		(property "Reference" "PC486_P1_7"
			(at 0 0 270)
			(layer "F.SilkS")
			(hide yes)
			(effects
				(font
					(size 1.27 1.27)
				)
			)
		)
		(property "Value" ""
			(at 0 0 270)
			(layer "F.Fab")
			(effects
				(font
					(size 1.27 1.27)
				)
			)
		)
		(duplicate_pad_numbers_are_jumpers no)
		(fp_line
			(start -0.7874 0.4064)
			(end -0.7874 -0.4064)
			(stroke
				(width 0.1524)
				(type default)
			)
			(layer "F.SilkS")
		)
		(fp_line
			(start 0.7874 0.4064)
			(end -0.7874 0.4064)
			(stroke
				(width 0.1524)
				(type default)
			)
			(layer "F.SilkS")
		)
		(fp_line
			(start -0.7874 -0.4064)
			(end 0.7874 -0.4064)
			(stroke
				(width 0.1524)
				(type default)
			)
			(layer "F.SilkS")
		)
		(fp_line
			(start 0.7874 -0.4064)
			(end 0.7874 0.4064)
			(stroke
				(width 0.1524)
				(type default)
			)
			(layer "F.SilkS")
		)
		(fp_line
			(start -0.67945 0.3048)
			(end -0.67945 -0.305054)
			(stroke
				(width 0.1)
				(type default)
			)
			(layer "F.Fab")
		)
		(fp_line
			(start -0.12065 0.3048)
			(end -0.67945 0.3048)
			(stroke
				(width 0.1)
				(type default)
			)
			(layer "F.Fab")
		)
		(fp_line
			(start 0.120396 0.3048)
			(end 0.120396 0.2794)
			(stroke
				(width 0.1)
				(type default)
			)
			(layer "F.Fab")
		)
		(fp_line
			(start 0.67945 0.3048)
			(end 0.120396 0.3048)
			(stroke
				(width 0.1)
				(type default)
			)
			(layer "F.Fab")
		)
		(fp_line
			(start -0.12065 0.2794)
			(end -0.12065 0.3048)
			(stroke
				(width 0.1)
				(type default)
			)
			(layer "F.Fab")
		)
		(fp_line
			(start 0.120396 0.2794)
			(end -0.12065 0.2794)
			(stroke
				(width 0.1)
				(type default)
			)
			(layer "F.Fab")
		)
		(fp_line
			(start -0.12065 -0.2794)
			(end 0.12065 -0.2794)
			(stroke
				(width 0.1)
				(type default)
			)
			(layer "F.Fab")
		)
		(fp_line
			(start 0.12065 -0.2794)
			(end 0.12065 -0.3048)
			(stroke
				(width 0.1)
				(type default)
			)
			(layer "F.Fab")
		)
		(fp_line
			(start 0.12065 -0.3048)
			(end 0.67945 -0.3048)
			(stroke
				(width 0.1)
				(type default)
			)
			(layer "F.Fab")
		)
		(fp_line
			(start 0.67945 -0.3048)
			(end 0.67945 0.3048)
			(stroke
				(width 0.1)
				(type default)
			)
			(layer "F.Fab")
		)
		(fp_line
			(start -0.67945 -0.305054)
			(end -0.12065 -0.305054)
			(stroke
				(width 0.1)
				(type default)
			)
			(layer "F.Fab")
		)
		(fp_line
			(start -0.12065 -0.305054)
			(end -0.12065 -0.2794)
			(stroke
				(width 0.1)
				(type default)
			)
			(layer "F.Fab")
		)
		(pad "1" smd circle
			(at -0.40005 0 270)
			(size 0 0)
			(layers "F.Cu" "F.Mask" "F.Paste")
			(net "SW_P12V_PVCCIN_CPU1_FLT")
		)
		(pad "2" smd circle
			(at 0.40005 0 270)
			(size 0 0)
			(layers "F.Cu" "F.Mask" "F.Paste")
			(net "GND")
		)
	)
)
